# T6G (Grand Teton) — schematic netlist excerpt (pin names and nets, part order shuffled) for the footprints in the layout excerpt that follows; sources: Cadence DE-HDL packaged netlist, KiCad conversion of 04192023_DAF0TMB3IC0_F0TG_MB_C_brd_V02_OCP.brd

J26  SCONN288_DDR506112002KQ  IO  pkg DDR288S_1-1VXC  page 99
  VIN_BULK0  = P12V_MEM_CPU1
  RFU0  = NC
  VIN_MGMT  = P3V3_AUX
  HSCL  = I3C_SPD_DDRB_CPU1_SCL
  HSDA  = I3C_SPD_DDRB_CPU1_SDA
  VSS0  = GND
  DQ0_A  = M_B_CPU1_SA_DQ<0>
  VSS1  = GND
  DQ1_A  = M_B_CPU1_SA_DQ<1>
  VSS2  = GND
  DQS0_A_T  = M_B_CPU1_SA_DQS_DP<0>
  DQS0_A_C  = M_B_CPU1_SA_DQS_DN<0>
  VSS3  = GND
  DQ4_A  = M_B_CPU1_SA_DQ<4>
  VSS4  = GND
  DQ5_A  = M_B_CPU1_SA_DQ<5>
  VSS5  = GND
  DQ8_A  = M_B_CPU1_SA_DQ<8>
  VSS6  = GND
  DQ9_A  = M_B_CPU1_SA_DQ<9>
  VSS7  = GND
  DQS1_A_T  = M_B_CPU1_SA_DQS_DP<1>
  DQS1_A_C  = M_B_CPU1_SA_DQS_DN<1>
  VSS8  = GND
  DQ12_A  = M_B_CPU1_SA_DQ<12>
  VSS9  = GND
  DQ13_A  = M_B_CPU1_SA_DQ<13>
  VSS10  = GND
  DQ16_A  = M_B_CPU1_SA_DQ<16>
  VSS11  = GND
  DQ17_A  = M_B_CPU1_SA_DQ<17>
  VSS12  = GND
  DQS2_A_T  = M_B_CPU1_SA_DQS_DP<2>
  DQS2_A_C  = M_B_CPU1_SA_DQS_DN<2>
  VSS13  = GND
  DQ20_A  = M_B_CPU1_SA_DQ<20>
  VSS14  = GND
  DQ21_A  = M_B_CPU1_SA_DQ<21>
  VSS15  = GND
  DQ24_A  = M_B_CPU1_SA_DQ<24>
  VSS16  = GND
  DQ25_A  = M_B_CPU1_SA_DQ<25>
  VSS17  = GND
  DQS3_A_T  = M_B_CPU1_SA_DQS_DP<3>
  DQS3_A_C  = M_B_CPU1_SA_DQS_DN<3>
  VSS18  = GND
  DQ28_A  = M_B_CPU1_SA_DQ<28>
  VSS19  = GND
  DQ29_A  = M_B_CPU1_SA_DQ<29>
  VSS20  = GND
  CB0_A  = M_B_CPU1_SA_CB<0>
  VSS21  = GND
  CB1_A  = M_B_CPU1_SA_CB<1>
  VSS22  = GND
  DQS4_A_T  = M_B_CPU1_SA_DQS_DP<4>
  DQS4_A_C  = M_B_CPU1_SA_DQS_DN<4>
  VSS23  = GND
  CB4_A  = M_B_CPU1_SA_CB<4>
  VSS24  = GND
  CB5_A  = M_B_CPU1_SA_CB<5>
  VSS25  = GND
  ALERT_N  = M_B_CPU1_ALERT_N
  VSS26  = GND
  CS0_A_N  = M_B_CPU1_SA_CS_N<0>
  VSS27  = GND
  CA0_A  = M_B_CPU1_SA_CA<0>
  VSS28  = GND
  CA2_A  = M_B_CPU1_SA_CA<2>
  VSS29  = GND
  CA4_A  = M_B_CPU1_SA_CA<4>
  VSS30  = GND
  CA6_A  = M_B_CPU1_SA_CA<6>
  VSS31  = GND
  PAR_A  = M_B_CPU1_SA_PAR
  VSS32  = GND
  CA0_B  = M_B_CPU1_SB_CA<0>
  VSS33  = GND
  CA2_B  = M_B_CPU1_SB_CA<2>
  VSS34  = GND
  CA4_B  = M_B_CPU1_SB_CA<4>
  VSS35  = GND
  CA6_B  = M_B_CPU1_SB_CA<6>
  VSS36  = GND
  CS0_B_N  = M_B_CPU1_SB_CS_N<0>
  VSS37  = GND
  \lbd||rsp_a_n\  = M_B_CPU1_SA_RSP<0>
  \lbs||rsp_b_n\  = M_B_CPU1_SB_RSP<0>
  VSS38  = GND
  CB4_B  = M_B_CPU1_SB_CB<4>
  VSS39  = GND
  CB5_B  = M_B_CPU1_SB_CB<5>
  VSS40  = GND
  \dqs9_b_t||tdqs9_b_t||dbi4_b_n\  = M_B_CPU1_SB_DQS_DP<9>
  \dqs9_b_c||tdqs9_b_c\  = M_B_CPU1_SB_DQS_DN<9>
  VSS41  = GND
  CB0_B  = M_B_CPU1_SB_CB<0>
  VSS42  = GND
  CB1_B  = M_B_CPU1_SB_CB<1>
  VSS43  = GND
  DQ0_B  = M_B_CPU1_SB_DQ<0>
  VSS44  = GND
  DQ1_B  = M_B_CPU1_SB_DQ<1>
  VSS45  = GND
  DQS0_B_T  = M_B_CPU1_SB_DQS_DP<0>
  DQS0_B_C  = M_B_CPU1_SB_DQS_DN<0>
  VSS46  = GND
  DQ4_B  = M_B_CPU1_SB_DQ<4>
  VSS47  = GND
  DQ5_B  = M_B_CPU1_SB_DQ<5>
  VSS48  = GND
  DQ8_B  = M_B_CPU1_SB_DQ<8>
  VSS49  = GND
  DQ9_B  = M_B_CPU1_SB_DQ<9>
  VSS50  = GND
  DQS1_B_T  = M_B_CPU1_SB_DQS_DP<1>
  DQS1_B_C  = M_B_CPU1_SB_DQS_DN<1>
  VSS51  = GND
  DQ12_B  = M_B_CPU1_SB_DQ<12>
  VSS52  = GND
  DQ13_B  = M_B_CPU1_SB_DQ<13>
  VSS53  = GND
  DQ16_B  = M_B_CPU1_SB_DQ<16>
  VSS54  = GND
  DQ17_B  = M_B_CPU1_SB_DQ<17>
  VSS55  = GND
  DQS2_B_T  = M_B_CPU1_SB_DQS_DP<2>
  DQS2_B_C  = M_B_CPU1_SB_DQS_DN<2>
  VSS56  = GND
  DQ20_B  = M_B_CPU1_SB_DQ<20>
  VSS57  = GND
  DQ21_B  = M_B_CPU1_SB_DQ<21>
  VSS58  = GND
  DQ24_B  = M_B_CPU1_SB_DQ<24>
  VSS59  = GND
  DQ25_B  = M_B_CPU1_SB_DQ<25>
  VSS60  = GND
  DQS3_B_T  = M_B_CPU1_SB_DQS_DP<3>
  DQS3_B_C  = M_B_CPU1_SB_DQS_DN<3>
  VSS61  = GND
  DQ28_B  = M_B_CPU1_SB_DQ<28>
  VSS62  = GND
  DQ29_B  = M_B_CPU1_SB_DQ<29>
  VSS63  = GND
  RFU1  = NC
  VIN_BULK1  = P12V_MEM_CPU1
  VIN_BULK2  = P12V_MEM_CPU1
  \pwr_good||fail_n\  = PWRGD_CHB_CPU1_DIMM
  HAS  = PD_CHB_CPU1_DIMM_SAA
  RFU2  = NC
  RFU3  = NC
  VSS64  = GND
  DQ2_A  = M_B_CPU1_SA_DQ<2>
  VSS65  = GND
  DQ3_A  = M_B_CPU1_SA_DQ<3>
  VSS66  = GND
  \dqs5_a_c||tdqs5_a_c||dqs5_a_t||tdqs5_a_t\  = M_B_CPU1_SA_DQS_DN<5>
  \dqs5_a_t||tdqs5_a_t\  = M_B_CPU1_SA_DQS_DP<5>
  VSS67  = GND
  DQ6_A  = M_B_CPU1_SA_DQ<6>
  VSS68  = GND
  DQ7_A  = M_B_CPU1_SA_DQ<7>
  VSS69  = GND
  DQ10_A  = M_B_CPU1_SA_DQ<10>
  VSS70  = GND
  DQ11_A  = M_B_CPU1_SA_DQ<11>
  VSS71  = GND
  \dqs6_a_c||tdqs6_a_c||dqs6_a_t||tdqs6_a_t\  = M_B_CPU1_SA_DQS_DN<6>
  \dqs6_a_t||tdqs6_a_t\  = M_B_CPU1_SA_DQS_DP<6>
  VSS72  = GND
  DQ14_A  = M_B_CPU1_SA_DQ<14>
  VSS73  = GND
  DQ15_A  = M_B_CPU1_SA_DQ<15>
  VSS74  = GND
  DQ18_A  = M_B_CPU1_SA_DQ<18>
  VSS75  = GND
  DQ19_A  = M_B_CPU1_SA_DQ<19>
  VSS76  = GND
  \dqs7_a_c||tdqs7_a_c\  = M_B_CPU1_SA_DQS_DN<7>
  \dqs7_a_t||tdqs7_a_t\  = M_B_CPU1_SA_DQS_DP<7>
  VSS77  = GND
  DQ22_A  = M_B_CPU1_SA_DQ<22>
  VSS78  = GND
  DQ23_A  = M_B_CPU1_SA_DQ<23>
  VSS79  = GND
  DQ26_A  = M_B_CPU1_SA_DQ<26>
  VSS80  = GND
  DQ27_A  = M_B_CPU1_SA_DQ<27>
  VSS81  = GND
  \dqs8_a_c||tdqs8_a_c\  = M_B_CPU1_SA_DQS_DN<8>
  \dqs8_a_t||tdqs8_a_t\  = M_B_CPU1_SA_DQS_DP<8>
  VSS82  = GND
  DQ30_A  = M_B_CPU1_SA_DQ<30>
  VSS83  = GND
  DQ31_A  = M_B_CPU1_SA_DQ<31>
  VSS84  = GND
  CB2_A  = M_B_CPU1_SA_CB<2>
  VSS85  = GND
  CB3_A  = M_B_CPU1_SA_CB<3>
  VSS86  = GND
  \dqs9_a_c||tdqs9_a_c\  = M_B_CPU1_SA_DQS_DN<9>
  \dqs9_a_t||tdqs9_a_t\  = M_B_CPU1_SA_DQS_DP<9>
  VSS87  = GND
  CB6_A  = M_B_CPU1_SA_CB<6>
  VSS88  = GND
  CB7_A  = M_B_CPU1_SA_CB<7>
  VSS89  = GND
  RESET_N  = M_B_CPU1_RESET_N
  VSS90  = GND
  CS1_A_N  = M_B_CPU1_SA_CS_N<1>
  VSS91  = GND
  CA1_A  = M_B_CPU1_SA_CA<1>
  VSS92  = GND
  CA3_A  = M_B_CPU1_SA_CA<3>
  VSS93  = GND
  CA5_A  = M_B_CPU1_SA_CA<5>
  VSS94  = GND
  CK_T  = M_B_CPU1_CLK_DP<0>
  CK_C  = M_B_CPU1_CLK_DN<0>
  VSS95  = GND
  RFU4  = NC
  CA1_B  = M_B_CPU1_SB_CA<1>
  VSS96  = GND
  CA3_B  = M_B_CPU1_SB_CA<3>
  VSS97  = GND
  CA5_B  = M_B_CPU1_SB_CA<5>
  VSS98  = GND
  PAR_B  = M_B_CPU1_SB_PAR
  VSS99  = GND
  CS1_B_N  = M_B_CPU1_SB_CS_N<1>
  VSS100  = GND
  RFU5  = NC
  RFU6  = NC
  VSS101  = GND
  CB6_B  = M_B_CPU1_SB_CB<6>
  VSS102  = GND
  CB7_B  = M_B_CPU1_SB_CB<7>
  VSS103  = GND
  DQS4_B_C  = M_B_CPU1_SB_DQS_DN<4>
  DQS4_B_T  = M_B_CPU1_SB_DQS_DP<4>
  VSS104  = GND
  CB2_B  = M_B_CPU1_SB_CB<2>
  VSS105  = GND
  CB3_B  = M_B_CPU1_SB_CB<3>
  VSS106  = GND
  DQ2_B  = M_B_CPU1_SB_DQ<2>
  VSS107  = GND
  DQ3_B  = M_B_CPU1_SB_DQ<3>
  VSS108  = GND
  \dqs5_b_c||tdqs5_b_c\  = M_B_CPU1_SB_DQS_DN<5>
  \dqs5_b_t||tdqs5_b_t\  = M_B_CPU1_SB_DQS_DP<5>
  VSS109  = GND
  DQ6_B  = M_B_CPU1_SB_DQ<6>
  VSS110  = GND
  DQ7_B  = M_B_CPU1_SB_DQ<7>
  VSS111  = GND
  DQ10_B  = M_B_CPU1_SB_DQ<10>
  VSS112  = GND
  DQ11_B  = M_B_CPU1_SB_DQ<11>
  VSS113  = GND
  \dqs6_b_c||tdqs6_b_c\  = M_B_CPU1_SB_DQS_DN<6>
  \dqs6_b_t||tdqs6_b_t\  = M_B_CPU1_SB_DQS_DP<6>
  VSS114  = GND
  DQ14_B  = M_B_CPU1_SB_DQ<14>
  VSS115  = GND
  DQ15_B  = M_B_CPU1_SB_DQ<15>
  VSS116  = GND
  DQ18_B  = M_B_CPU1_SB_DQ<18>
  VSS117  = GND
  DQ19_B  = M_B_CPU1_SB_DQ<19>
  VSS118  = GND
  \dqs7_b_c||tdqs7_b_c\  = M_B_CPU1_SB_DQS_DN<7>
  \dqs7_b_t||tdqs7_b_t\  = M_B_CPU1_SB_DQS_DP<7>
  VSS119  = GND
  DQ22_B  = M_B_CPU1_SB_DQ<22>
  VSS120  = GND
  DQ23_B  = M_B_CPU1_SB_DQ<23>
  VSS121  = GND
  DQ26_B  = M_B_CPU1_SB_DQ<26>
  VSS122  = GND
  DQ27_B  = M_B_CPU1_SB_DQ<27>
  VSS123  = GND
  \dqs8_b_c||tdqs8_b_c\  = M_B_CPU1_SB_DQS_DN<8>
  \dqs8_b_t||tdqs8_b_t\  = M_B_CPU1_SB_DQS_DP<8>
  VSS124  = GND
  DQ30_B  = M_B_CPU1_SB_DQ<30>
  VSS125  = GND
  DQ31_B  = M_B_CPU1_SB_DQ<31>
  VSS126  = GND
  G1  = GND
  G2  = GND
  G3  = GND

(kicad_pcb
	(version 20260206)
	(generator "pcbnew")
	(generator_version "10.0")
	(general
		(thickness 1.6)
		(legacy_teardrops no)
	)
	(paper "A4")
	(title_block
		(title "04192023_DAF0TMB3IC0_F0TG_MB_C_brd_V02_OCP.brd")
		(comment 1 "Grand Teton / footprint 4371 of 8354 (J26), pads 93-138 of 291")
	)
	(layers
		(0 "F.Cu" signal "TOP")
		(4 "In1.Cu" signal "GND")
		(6 "In2.Cu" signal "IN1")
		(8 "In3.Cu" signal "GND1")
		(10 "In4.Cu" signal "IN2")
		(12 "In5.Cu" signal "GND2")
		(14 "In6.Cu" signal "IN3")
		(16 "In7.Cu" signal "GND3")
		(18 "In8.Cu" signal "VCC")
		(20 "In9.Cu" signal "VCC1")
		(22 "In10.Cu" signal "GND4")
		(24 "In11.Cu" signal "IN4")
		(26 "In12.Cu" signal "GND5")
		(28 "In13.Cu" signal "IN5")
		(30 "In14.Cu" signal "GND6")
		(32 "In15.Cu" signal "IN6")
		(34 "In16.Cu" signal "GND7")
		(2 "B.Cu" signal "BOTTOM")
		(9 "F.Adhes" user "F.Adhesive")
		(11 "B.Adhes" user "B.Adhesive")
		(13 "F.Paste" user "Package Geometry/Pastemask Top")
		(15 "B.Paste" user "Package Geometry/Pastemask Bottom")
		(5 "F.SilkS" user "Ref Des/Silkscreen Top")
		(7 "B.SilkS" user "Ref Des/Silkscreen Bottom")
		(1 "F.Mask" user "Board Geometry/Soldermask Top")
		(3 "B.Mask" user "Board Geometry/Soldermask Bottom")
		(17 "Dwgs.User" user "User.Drawings")
		(19 "Cmts.User" user "User.Comments")
		(21 "Eco1.User" user "User.Eco1")
		(23 "Eco2.User" user "User.Eco2")
		(25 "Edge.Cuts" user "Board Geometry/Outline")
		(27 "Margin" user)
		(31 "F.CrtYd" user "Package Geometry/Place Bound Top")
		(29 "B.CrtYd" user "Package Geometry/Place Bound Bottom")
		(35 "F.Fab" user "Ref Des/Assembly Top")
		(33 "B.Fab" user "Ref Des/Assembly Bottom")
	)
	(footprint ""
		(layer "F.Cu")
		(at 49.834038 -255.560322 180)
		(property "Reference" "J26"
			(at -0.703326 -82.357722 0)
			(unlocked yes)
			(layer "F.SilkS")
			(effects
				(font
					(size 0.7874 0.5842)
					(thickness 0.1524)
				)
			)
		)
		(property "Value" ""
			(at 0 0 180)
			(layer "F.Fab")
			(effects
				(font
					(size 1.27 1.27)
				)
			)
		)
		(duplicate_pad_numbers_are_jumpers no)
		(pad "93" smd rect
			(at -2.050034 19.975068 90)
			(size 0.519938 1.4986)
			(layers "F.Cu" "F.Mask" "F.Paste")
			(net "M_B_CPU1_SB_DQS_DP<9>")
		)
		(pad "94" smd rect
			(at -2.050034 20.824952 90)
			(size 0.519938 1.4986)
			(layers "F.Cu" "F.Mask" "F.Paste")
			(net "M_B_CPU1_SB_DQS_DN<9>")
		)
		(pad "95" smd rect
			(at -2.050034 21.67509 90)
			(size 0.519938 1.4986)
			(layers "F.Cu" "F.Mask" "F.Paste")
			(net "GND")
		)
		(pad "96" smd rect
			(at -2.050034 22.524974 90)
			(size 0.519938 1.4986)
			(layers "F.Cu" "F.Mask" "F.Paste")
			(net "M_B_CPU1_SB_CB<0>")
		)
		(pad "97" smd rect
			(at -2.050034 23.375112 90)
			(size 0.519938 1.4986)
			(layers "F.Cu" "F.Mask" "F.Paste")
			(net "GND")
		)
		(pad "98" smd rect
			(at -2.050034 24.224996 90)
			(size 0.519938 1.4986)
			(layers "F.Cu" "F.Mask" "F.Paste")
			(net "M_B_CPU1_SB_CB<1>")
		)
		(pad "99" smd rect
			(at -2.050034 25.07488 90)
			(size 0.519938 1.4986)
			(layers "F.Cu" "F.Mask" "F.Paste")
			(net "GND")
		)
		(pad "100" smd rect
			(at -2.050034 25.925018 90)
			(size 0.519938 1.4986)
			(layers "F.Cu" "F.Mask" "F.Paste")
			(net "M_B_CPU1_SB_DQ<0>")
		)
		(pad "101" smd rect
			(at -2.050034 26.774902 90)
			(size 0.519938 1.4986)
			(layers "F.Cu" "F.Mask" "F.Paste")
			(net "GND")
		)
		(pad "102" smd rect
			(at -2.050034 27.62504 90)
			(size 0.519938 1.4986)
			(layers "F.Cu" "F.Mask" "F.Paste")
			(net "M_B_CPU1_SB_DQ<1>")
		)
		(pad "103" smd rect
			(at -2.050034 28.474924 90)
			(size 0.519938 1.4986)
			(layers "F.Cu" "F.Mask" "F.Paste")
			(net "GND")
		)
		(pad "104" smd rect
			(at -2.050034 29.325062 90)
			(size 0.519938 1.4986)
			(layers "F.Cu" "F.Mask" "F.Paste")
			(net "M_B_CPU1_SB_DQS_DP<0>")
		)
		(pad "105" smd rect
			(at -2.050034 30.174946 90)
			(size 0.519938 1.4986)
			(layers "F.Cu" "F.Mask" "F.Paste")
			(net "M_B_CPU1_SB_DQS_DN<0>")
		)
		(pad "106" smd rect
			(at -2.050034 31.025084 90)
			(size 0.519938 1.4986)
			(layers "F.Cu" "F.Mask" "F.Paste")
			(net "GND")
		)
		(pad "107" smd rect
			(at -2.050034 31.874968 90)
			(size 0.519938 1.4986)
			(layers "F.Cu" "F.Mask" "F.Paste")
			(net "M_B_CPU1_SB_DQ<4>")
		)
		(pad "108" smd rect
			(at -2.050034 32.725106 90)
			(size 0.519938 1.4986)
			(layers "F.Cu" "F.Mask" "F.Paste")
			(net "GND")
		)
		(pad "109" smd rect
			(at -2.050034 33.57499 90)
			(size 0.519938 1.4986)
			(layers "F.Cu" "F.Mask" "F.Paste")
			(net "M_B_CPU1_SB_DQ<5>")
		)
		(pad "110" smd rect
			(at -2.050034 34.425128 90)
			(size 0.519938 1.4986)
			(layers "F.Cu" "F.Mask" "F.Paste")
			(net "GND")
		)
		(pad "111" smd rect
			(at -2.050034 35.275012 90)
			(size 0.519938 1.4986)
			(layers "F.Cu" "F.Mask" "F.Paste")
			(net "M_B_CPU1_SB_DQ<8>")
		)
		(pad "112" smd rect
			(at -2.050034 36.124896 90)
			(size 0.519938 1.4986)
			(layers "F.Cu" "F.Mask" "F.Paste")
			(net "GND")
		)
		(pad "113" smd rect
			(at -2.050034 36.975034 90)
			(size 0.519938 1.4986)
			(layers "F.Cu" "F.Mask" "F.Paste")
			(net "M_B_CPU1_SB_DQ<9>")
		)
		(pad "114" smd rect
			(at -2.050034 37.824918 90)
			(size 0.519938 1.4986)
			(layers "F.Cu" "F.Mask" "F.Paste")
			(net "GND")
		)
		(pad "115" smd rect
			(at -2.050034 38.675056 90)
			(size 0.519938 1.4986)
			(layers "F.Cu" "F.Mask" "F.Paste")
			(net "M_B_CPU1_SB_DQS_DP<1>")
		)
		(pad "116" smd rect
			(at -2.050034 39.52494 90)
			(size 0.519938 1.4986)
			(layers "F.Cu" "F.Mask" "F.Paste")
			(net "M_B_CPU1_SB_DQS_DN<1>")
		)
		(pad "117" smd rect
			(at -2.050034 40.375078 90)
			(size 0.519938 1.4986)
			(layers "F.Cu" "F.Mask" "F.Paste")
			(net "GND")
		)
		(pad "118" smd rect
			(at -2.050034 41.224962 90)
			(size 0.519938 1.4986)
			(layers "F.Cu" "F.Mask" "F.Paste")
			(net "M_B_CPU1_SB_DQ<12>")
		)
		(pad "119" smd rect
			(at -2.050034 42.0751 90)
			(size 0.519938 1.4986)
			(layers "F.Cu" "F.Mask" "F.Paste")
			(net "GND")
		)
		(pad "120" smd rect
			(at -2.050034 42.924984 90)
			(size 0.519938 1.4986)
			(layers "F.Cu" "F.Mask" "F.Paste")
			(net "M_B_CPU1_SB_DQ<13>")
		)
		(pad "121" smd rect
			(at -2.050034 43.775122 90)
			(size 0.519938 1.4986)
			(layers "F.Cu" "F.Mask" "F.Paste")
			(net "GND")
		)
		(pad "122" smd rect
			(at -2.050034 44.625006 90)
			(size 0.519938 1.4986)
			(layers "F.Cu" "F.Mask" "F.Paste")
			(net "M_B_CPU1_SB_DQ<16>")
		)
		(pad "123" smd rect
			(at -2.050034 45.47489 90)
			(size 0.519938 1.4986)
			(layers "F.Cu" "F.Mask" "F.Paste")
			(net "GND")
		)
		(pad "124" smd rect
			(at -2.050034 46.325028 90)
			(size 0.519938 1.4986)
			(layers "F.Cu" "F.Mask" "F.Paste")
			(net "M_B_CPU1_SB_DQ<17>")
		)
		(pad "125" smd rect
			(at -2.050034 47.174912 90)
			(size 0.519938 1.4986)
			(layers "F.Cu" "F.Mask" "F.Paste")
			(net "GND")
		)
		(pad "126" smd rect
			(at -2.050034 48.02505 90)
			(size 0.519938 1.4986)
			(layers "F.Cu" "F.Mask" "F.Paste")
			(net "M_B_CPU1_SB_DQS_DP<2>")
		)
		(pad "127" smd rect
			(at -2.050034 48.874934 90)
			(size 0.519938 1.4986)
			(layers "F.Cu" "F.Mask" "F.Paste")
			(net "M_B_CPU1_SB_DQS_DN<2>")
		)
		(pad "128" smd rect
			(at -2.050034 49.725072 90)
			(size 0.519938 1.4986)
			(layers "F.Cu" "F.Mask" "F.Paste")
			(net "GND")
		)
		(pad "129" smd rect
			(at -2.050034 50.574956 90)
			(size 0.519938 1.4986)
			(layers "F.Cu" "F.Mask" "F.Paste")
			(net "M_B_CPU1_SB_DQ<20>")
		)
		(pad "130" smd rect
			(at -2.050034 51.425094 90)
			(size 0.519938 1.4986)
			(layers "F.Cu" "F.Mask" "F.Paste")
			(net "GND")
		)
		(pad "131" smd rect
			(at -2.050034 52.274978 90)
			(size 0.519938 1.4986)
			(layers "F.Cu" "F.Mask" "F.Paste")
			(net "M_B_CPU1_SB_DQ<21>")
		)
		(pad "132" smd rect
			(at -2.050034 53.125116 90)
			(size 0.519938 1.4986)
			(layers "F.Cu" "F.Mask" "F.Paste")
			(net "GND")
		)
		(pad "133" smd rect
			(at -2.050034 53.975 90)
			(size 0.519938 1.4986)
			(layers "F.Cu" "F.Mask" "F.Paste")
			(net "M_B_CPU1_SB_DQ<24>")
		)
		(pad "134" smd rect
			(at -2.050034 54.824884 90)
			(size 0.519938 1.4986)
			(layers "F.Cu" "F.Mask" "F.Paste")
			(net "GND")
		)
		(pad "135" smd rect
			(at -2.050034 55.675022 90)
			(size 0.519938 1.4986)
			(layers "F.Cu" "F.Mask" "F.Paste")
			(net "M_B_CPU1_SB_DQ<25>")
		)
		(pad "136" smd rect
			(at -2.050034 56.524906 90)
			(size 0.519938 1.4986)
			(layers "F.Cu" "F.Mask" "F.Paste")
			(net "GND")
		)
		(pad "137" smd rect
			(at -2.050034 57.375044 90)
			(size 0.519938 1.4986)
			(layers "F.Cu" "F.Mask" "F.Paste")
			(net "M_B_CPU1_SB_DQS_DP<3>")
		)
		(pad "138" smd rect
			(at -2.050034 58.224928 90)
			(size 0.519938 1.4986)
			(layers "F.Cu" "F.Mask" "F.Paste")
			(net "M_B_CPU1_SB_DQS_DN<3>")
		)
	)
)
